# T6G (Grand Teton) — schematic netlist excerpt (pin names and nets, part order shuffled) for the footprints in the layout excerpt that follows; sources: Cadence DE-HDL packaged netlist, KiCad conversion of 04192023_DAF0TMB3IC0_F0TG_MB_C_brd_V02_OCP.brd

PC8012  Q_CAP  22UF 16V 20% X6S  pkg C0805  page 215 : A = SW_P12V_AUX_PVDDCR_SOC_P1_FLT ; B = GND
C518  Q_CAP  10UF 25V 10% X6S  pkg C0805  page 103 : A = P12V_MEM_CPU1 ; B = GND
PC415_4  Q_CAP  22UF 16V 20% X6S  pkg C0805  page 219 : A = SW_P12V_AUX_PVDDCR_CPU1_P1_FLT ; B = GND

(kicad_pcb
	(version 20260206)
	(generator "pcbnew")
	(generator_version "10.0")
	(general
		(thickness 1.6)
		(legacy_teardrops no)
	)
	(paper "A4")
	(title_block
		(title "04192023_DAF0TMB3IC0_F0TG_MB_C_brd_V02_OCP.brd")
		(comment 1 "Grand Teton / footprints 8167-8169 of 8354")
	)
	(layers
		(0 "F.Cu" signal "TOP")
		(4 "In1.Cu" signal "GND")
		(6 "In2.Cu" signal "IN1")
		(8 "In3.Cu" signal "GND1")
		(10 "In4.Cu" signal "IN2")
		(12 "In5.Cu" signal "GND2")
		(14 "In6.Cu" signal "IN3")
		(16 "In7.Cu" signal "GND3")
		(18 "In8.Cu" signal "VCC")
		(20 "In9.Cu" signal "VCC1")
		(22 "In10.Cu" signal "GND4")
		(24 "In11.Cu" signal "IN4")
		(26 "In12.Cu" signal "GND5")
		(28 "In13.Cu" signal "IN5")
		(30 "In14.Cu" signal "GND6")
		(32 "In15.Cu" signal "IN6")
		(34 "In16.Cu" signal "GND7")
		(2 "B.Cu" signal "BOTTOM")
		(9 "F.Adhes" user "F.Adhesive")
		(11 "B.Adhes" user "B.Adhesive")
		(13 "F.Paste" user "Package Geometry/Pastemask Top")
		(15 "B.Paste" user "Package Geometry/Pastemask Bottom")
		(5 "F.SilkS" user "Ref Des/Silkscreen Top")
		(7 "B.SilkS" user "Ref Des/Silkscreen Bottom")
		(1 "F.Mask" user "Board Geometry/Soldermask Top")
		(3 "B.Mask" user "Board Geometry/Soldermask Bottom")
		(17 "Dwgs.User" user "User.Drawings")
		(19 "Cmts.User" user "User.Comments")
		(21 "Eco1.User" user "User.Eco1")
		(23 "Eco2.User" user "User.Eco2")
		(25 "Edge.Cuts" user "Board Geometry/Outline")
		(27 "Margin" user)
		(31 "F.CrtYd" user "Package Geometry/Place Bound Top")
		(29 "B.CrtYd" user "Package Geometry/Place Bound Bottom")
		(35 "F.Fab" user "Ref Des/Assembly Top")
		(33 "B.Fab" user "Ref Des/Assembly Bottom")
	)
	(footprint ""
		(layer "B.Cu")
		(at 17.608042 -192.66027 180)
		(property "Reference" "C518"
			(at 0 0 0)
			(layer "B.SilkS")
			(hide yes)
			(effects
				(font
					(size 1.27 1.27)
				)
				(justify mirror)
			)
		)
		(property "Value" ""
			(at 0 0 0)
			(layer "B.Fab")
			(effects
				(font
					(size 1.27 1.27)
				)
				(justify mirror)
			)
		)
		(duplicate_pad_numbers_are_jumpers no)
		(fp_line
			(start 1.524 0.762)
			(end 1.524 -0.762)
			(stroke
				(width 0.1524)
				(type default)
			)
			(layer "B.SilkS")
		)
		(fp_line
			(start 1.524 -0.762)
			(end -1.524 -0.762)
			(stroke
				(width 0.1524)
				(type default)
			)
			(layer "B.SilkS")
		)
		(fp_line
			(start -1.524 0.762)
			(end 1.524 0.762)
			(stroke
				(width 0.1524)
				(type default)
			)
			(layer "B.SilkS")
		)
		(fp_line
			(start -1.524 -0.762)
			(end -1.524 0.762)
			(stroke
				(width 0.1524)
				(type default)
			)
			(layer "B.SilkS")
		)
		(fp_line
			(start 1.1049 0.724916)
			(end -1.1049 0.724916)
			(stroke
				(width 0.1)
				(type default)
			)
			(layer "B.Fab")
		)
		(fp_line
			(start 1.1049 -0.724916)
			(end 1.1049 0.724916)
			(stroke
				(width 0.1)
				(type default)
			)
			(layer "B.Fab")
		)
		(fp_line
			(start -1.1049 0.724916)
			(end -1.1049 -0.724916)
			(stroke
				(width 0.1)
				(type default)
			)
			(layer "B.Fab")
		)
		(fp_line
			(start -1.1049 -0.724916)
			(end 1.1049 -0.724916)
			(stroke
				(width 0.1)
				(type default)
			)
			(layer "B.Fab")
		)
		(pad "1" smd rect
			(at 0.889 0 180)
			(size 1.016 1.27)
			(layers "B.Cu" "B.Mask" "B.Paste")
			(net "P12V_MEM_CPU1")
		)
		(pad "2" smd rect
			(at -0.889 0 180)
			(size 1.016 1.27)
			(layers "B.Cu" "B.Mask" "B.Paste")
			(net "GND")
		)
	)
	(footprint ""
		(layer "B.Cu")
		(at 62.996318 -350.660716 -90)
		(property "Reference" "PC415_4"
			(at 0 0 90)
			(layer "B.SilkS")
			(hide yes)
			(effects
				(font
					(size 1.27 1.27)
				)
				(justify mirror)
			)
		)
		(property "Value" ""
			(at 0 0 90)
			(layer "B.Fab")
			(effects
				(font
					(size 1.27 1.27)
				)
				(justify mirror)
			)
		)
		(duplicate_pad_numbers_are_jumpers no)
		(fp_line
			(start -1.524 0.762)
			(end 1.524 0.762)
			(stroke
				(width 0.1524)
				(type default)
			)
			(layer "B.SilkS")
		)
		(fp_line
			(start 1.524 0.762)
			(end 1.524 -0.762)
			(stroke
				(width 0.1524)
				(type default)
			)
			(layer "B.SilkS")
		)
		(fp_line
			(start -1.524 -0.762)
			(end -1.524 0.762)
			(stroke
				(width 0.1524)
				(type default)
			)
			(layer "B.SilkS")
		)
		(fp_line
			(start 1.524 -0.762)
			(end -1.524 -0.762)
			(stroke
				(width 0.1524)
				(type default)
			)
			(layer "B.SilkS")
		)
		(fp_line
			(start -1.1049 0.724916)
			(end -1.1049 -0.724916)
			(stroke
				(width 0.1)
				(type default)
			)
			(layer "B.Fab")
		)
		(fp_line
			(start 1.1049 0.724916)
			(end -1.1049 0.724916)
			(stroke
				(width 0.1)
				(type default)
			)
			(layer "B.Fab")
		)
		(fp_line
			(start -1.1049 -0.724916)
			(end 1.1049 -0.724916)
			(stroke
				(width 0.1)
				(type default)
			)
			(layer "B.Fab")
		)
		(fp_line
			(start 1.1049 -0.724916)
			(end 1.1049 0.724916)
			(stroke
				(width 0.1)
				(type default)
			)
			(layer "B.Fab")
		)
		(pad "1" smd rect
			(at 0.889 0 270)
			(size 1.016 1.27)
			(layers "B.Cu" "B.Mask" "B.Paste")
			(net "SW_P12V_AUX_PVDDCR_CPU1_P1_FLT")
		)
		(pad "2" smd rect
			(at -0.889 0 270)
			(size 1.016 1.27)
			(layers "B.Cu" "B.Mask" "B.Paste")
			(net "GND")
		)
	)
	(footprint ""
		(layer "B.Cu")
		(at 117.351302 -165.040056 -90)
		(property "Reference" "PC8012"
			(at 0 0 90)
			(layer "B.SilkS")
			(hide yes)
			(effects
				(font
					(size 1.27 1.27)
				)
				(justify mirror)
			)
		)
		(property "Value" ""
			(at 0 0 90)
			(layer "B.Fab")
			(effects
				(font
					(size 1.27 1.27)
				)
				(justify mirror)
			)
		)
		(duplicate_pad_numbers_are_jumpers no)
		(fp_line
			(start -1.524 0.762)
			(end 1.524 0.762)
			(stroke
				(width 0.1524)
				(type default)
			)
			(layer "B.SilkS")
		)
		(fp_line
			(start 1.524 0.762)
			(end 1.524 -0.762)
			(stroke
				(width 0.1524)
				(type default)
			)
			(layer "B.SilkS")
		)
		(fp_line
			(start -1.524 -0.762)
			(end -1.524 0.762)
			(stroke
				(width 0.1524)
				(type default)
			)
			(layer "B.SilkS")
		)
		(fp_line
			(start 1.524 -0.762)
			(end -1.524 -0.762)
			(stroke
				(width 0.1524)
				(type default)
			)
			(layer "B.SilkS")
		)
		(fp_line
			(start -1.1049 0.724916)
			(end -1.1049 -0.724916)
			(stroke
				(width 0.1)
				(type default)
			)
			(layer "B.Fab")
		)
		(fp_line
			(start 1.1049 0.724916)
			(end -1.1049 0.724916)
			(stroke
				(width 0.1)
				(type default)
			)
			(layer "B.Fab")
		)
		(fp_line
			(start -1.1049 -0.724916)
			(end 1.1049 -0.724916)
			(stroke
				(width 0.1)
				(type default)
			)
			(layer "B.Fab")
		)
		(fp_line
			(start 1.1049 -0.724916)
			(end 1.1049 0.724916)
			(stroke
				(width 0.1)
				(type default)
			)
			(layer "B.Fab")
		)
		(pad "1" smd rect
			(at 0.889 0 270)
			(size 1.016 1.27)
			(layers "B.Cu" "B.Mask" "B.Paste")
			(net "SW_P12V_AUX_PVDDCR_SOC_P1_FLT")
		)
		(pad "2" smd rect
			(at -0.889 0 270)
			(size 1.016 1.27)
			(layers "B.Cu" "B.Mask" "B.Paste")
			(net "GND")
		)
	)
)
